FILE_TYPE = CONNECTIVITY;
{Allegro Design Entry HDL 17.4-2019 S026 (4007227) 1/17/2022}
"PAGE_NUMBER" = 378;
0"NC";
1"GND\g";
2"GND\g";
3"GND\g";
4"GND\g";
5"RST_SMB_RT_R1_N";
6"SMB_MUX_RT_SCL";
7"SMB_MUX_RT_R1_SCL";
8"SMB_MUX_RT_SDA";
9"SMB_MUX_RT_R1_SDA";
10"SMB_RT_CPU0_P0_R_SCL";
11"SMB_RT_CPU0_P1_SDA";
12"SMB_RT_CPU0_P0_SCL";
13"SMB_RT_CPU0_P0_SDA";
14"SMB_MUX_RT_R2_SDA";
15"SMB_RT_CPU0_P0_R_SDA";
16"SMB_RT_CPU0_P1_R_SDA";
17"SMB_RT_CPU0_P1_R_SCL";
18"SMB_RT_CPU0_P3_R_SCL";
19"SMB_RT_CPU0_P2_R_SCL";
20"SMB_MUX_RT_R2_SCL";
21"GND\g";
22"P1V8_AUX\g";
23"P1V8_CPU0_RT_1D\g";
24"P1V8_CPU1_RT_1D\g";
25"P1V8_AUX\g";
26"SMB_RT_CPU0_P2_R_SDA";
27"SMB_RT_CPU0_P3_R_SDA";
28"SMB_RT_CPU1_P3_R_SDA";
29"SMB_RT_CPU1_P3_R_SCL";
30"SMB_RT_CPU1_P2_R_SCL";
31"SMB_RT_CPU1_P1_R_SCL";
32"SMB_RT_CPU1_P0_R_SDA";
33"SMB_RT_CPU1_P0_R_SCL";
34"SMB_RT_CPU1_P1_R_SDA";
35"SMB_RT_CPU1_P1_R_SCL";
36"SMB_RT_CPU1_P3_R_SCL";
37"SMB_RT_CPU1_P3_R_SDA";
38"SMB_RT_CPU1_P2_R_SDA";
39"SMB_RT_CPU1_P2_R_SCL";
40"SMB_RT_CPU0_P0_R_SDA";
41"SMB_RT_CPU0_P0_R_SCL";
42"SMB_RT_CPU0_P1_R_SCL";
43"SMB_RT_CPU0_P3_R_SDA";
44"SMB_RT_CPU0_P3_R_SCL";
45"SMB_RT_CPU0_P2_R_SDA";
46"SMB_RT_CPU0_P2_R_SCL";
47"RT_SMB_MUX_ADDR2";
48"RT_SMB_MUX_ADDR0";
49"RT_SMB_MUX_ADDR1";
50"SMB_RT_CPU1_P0_R_SDA";
51"SMB_RT_CPU1_P3_SCL";
52"SMB_RT_CPU0_P1_R_SDA";
53"SMB_RT_CPU1_P0_R_SCL";
54"SMB_RT_CPU1_P1_R_SDA";
55"SMB_RT_CPU1_P2_SDA";
56"SMB_RT_CPU1_P2_SCL";
57"SMB_RT_CPU1_P0_SDA";
58"SMB_RT_CPU1_P2_R_SDA";
59"RST_SMB_RT_R1_N";
60"SMB_RT_CPU0_P3_SDA";
61"SMB_RT_CPU0_P1_SCL";
62"SMB_RT_CPU1_P1_SDA";
63"SMB_RT_CPU1_P0_SCL";
64"SMB_RT_CPU1_P3_SDA";
65"SMB_RT_CPU1_P1_SCL";
66"SMB_RT_CPU0_P3_SCL";
67"SMB_RT_CPU0_P2_SDA";
68"SMB_RT_CPU0_P2_SCL";
69"RT_SMB_MUX_ADDR0";
70"RT_SMB_MUX_ADDR1";
71"RST_SMB_RT_N";
72"RT_SMB_MUX_ADDR2";
%"TCA9548APWR"
"1","(-4900,4575)","0","pure_quanta","I1";
;
LOCATION"U6020"
$SEC"1"
CDS_SEC"1"
MATERIAL"IC"
PART_TYPE"SMLF"
VALUE"TCA9548APWR"
CDS_LIB"pure_quanta"
CDS_LMAN_SYM_OUTLINE"-200,475,200,-475"
NEEDS_NO_SIZE"TRUE"
PART_NUMBER"AL009548K02";
"SD4"
$PN"13"13;
"SC4"
$PN"14"12;
"SD5"
$PN"15"11;
"SC5"
$PN"16"61;
"SD6"
$PN"17"60;
"SC6"
$PN"18"66;
"SD7"
$PN"19"67;
"SC7"
$PN"20"68;
"A2"
$PN"21"72;
"SCL"
$PN"22"6;
"SDA"
$PN"23"8;
"VCC"
$PN"24"22;
"GND"
$PN"12"3;
"SC3"
$PN"11"56;
"SD3"
$PN"10"55;
"SC2"
$PN"9"51;
"SD2"
$PN"8"64;
"SC1"
$PN"7"65;
"SD1"
$PN"6"62;
"SC0"
$PN"5"63;
"SD0"
$PN"4"57;
"RESET# \B"
$PN"3"71;
"A1"
$PN"2"70;
"A0"
$PN"1"69;
%"Q_RES"
"2","(-8300,1800)","0","pure_quanta","I100";
;
LOCATION"R6771"
$SEC"1"
CDS_SEC"1"
PACK_TYPE"0201LF"
MATERIAL"EMPTY"
WATTAGE"1/20W"
VALUE"4.7K"
TOLERANCE"5%"
CDS_LIB"pure_quanta"
PART_NUMBER"CS24701JE04";
"A"
$PN"1"25;
"B"
$PN"2"49;
%"Q_RES"
"1","(-6700,4700)","0","pure_quanta","I104";
;
LOCATION"R6776"
$SEC"1"
CDS_SEC"1"
TOLERANCE"5%"
VALUE"0"
PACK_TYPE"0201LF"
MATERIAL"CHIP"
WATTAGE"1/20W"
CDS_LIB"pure_quanta"
PART_NUMBER"CS00001JE10";
"B"
$PN"2"71;
"A"
$PN"1"59;
%"Q_RES"
"2","(-6975,3000)","0","pure_quanta","I107";
;
LOCATION"R6778"
$SEC"1"
CDS_SEC"1"
VALUE"10K"
MATERIAL"CHIP"
WATTAGE"1/20W"
TOLERANCE"1%"
PACK_TYPE"0201LF"
CDS_LIB"pure_quanta"
PART_NUMBER"CS31001FE17";
"A"
$PN"1"5;
"B"
$PN"2"1;
%"UNIVERSAL_GND"
"1","(-6975,2325)","0","pure_quanta_power","I108";
;
CDS_LIB"pure_quanta_power"
HDL_POWER"GND";
"A"1;
%"Q_RES"
"1","(-2625,1350)","0","pure_quanta","I11";
;
LOCATION"R6719"
$SEC"1"
CDS_SEC"1"
VALUE"1K"
MATERIAL"CHIP"
PACK_TYPE"0201LF"
TOLERANCE"1%"
WATTAGE"1/20W"
CDS_LIB"pure_quanta"
PART_NUMBER"CS21001FE07";
"B"
$PN"2"33;
"A"
$PN"1"24;
%"P1V0_AUX"
"1","(-8600,2225)","0","pure_quanta_power","I113";
;
HDL_POWER"P1V8_AUX"
CDS_LIB"pure_quanta_power";
"A"25;
%"UNIVERSAL_GND"
"1","(-1225,5225)","0","pure_quanta_power","I115";
;
CDS_LIB"pure_quanta_power"
HDL_POWER"GND";
"A"2;
%"CONN3_210HP1030BR1"
"1","(-800,5450)","0","pure_quanta","I116";
;
LOCATION"JP6500"
$SEC"1"
CDS_SEC"1"
PART_TYPE"THLF"
MATERIAL"IO"
VALUE"CONN3_210-HP1-030BR1"
CDS_LIB"pure_quanta"
CDS_LMAN_SYM_OUTLINE"-50,100,50,-100"
NEEDS_NO_SIZE"TRUE"
PART_NUMBER"DFHD03MS213";
"1"
$PN"1"20;
"2"
$PN"2"14;
"3"
$PN"3"2;
%"Q_RES"
"1","(-2150,5450)","0","pure_quanta","I117";
;
LOCATION"R1515"
$SEC"1"
CDS_SEC"1"
TOLERANCE"5%"
MATERIAL"CHIP"
PACK_TYPE"0201LF"
VALUE"0"
CDS_LIB"pure_quanta"
WATTAGE"1/20W"
PART_NUMBER"CS00001JE10";
"B"
$PN"2"14;
"A"
$PN"1"9;
%"Q_RES"
"1","(-2150,5500)","0","pure_quanta","I118";
;
LOCATION"R1514"
$SEC"1"
CDS_SEC"1"
VALUE"0"
PACK_TYPE"0201LF"
MATERIAL"CHIP"
TOLERANCE"5%"
CDS_LIB"pure_quanta"
WATTAGE"1/20W"
PART_NUMBER"CS00001JE10";
"B"
$PN"2"20;
"A"
$PN"1"7;
%"Q_RES"
"1","(-3050,4850)","0","pure_quanta","I119";
;
LOCATION"R6779"
SEC"1"
VALUE"33.2"
TOLERANCE"1%"
MATERIAL"CHIP"
PACK_TYPE"0201LF"
CDS_LIB"pure_quanta"
SEC_TYPE"0201LF"
WATTAGE"1/20W"
PART_NUMBER"CS03321FE09";
"B"
$PN"2"9;
"A"
$PN"1"8;
%"Q_RES"
"1","(-3050,4800)","0","pure_quanta","I120";
;
LOCATION"R6780"
SEC"1"
VALUE"33.2"
TOLERANCE"1%"
MATERIAL"CHIP"
PACK_TYPE"0201LF"
WATTAGE"1/20W"
CDS_LIB"pure_quanta"
SEC_TYPE"0201LF"
PART_NUMBER"CS03321FE09";
"B"
$PN"2"7;
"A"
$PN"1"6;
%"Q_RES"
"1","(-6350,4500)","0","pure_quanta","I13";
;
LOCATION"R6736"
$SEC"1"
CDS_SEC"1"
TOLERANCE"5%"
MATERIAL"CHIP"
VALUE"0"
PACK_TYPE"0201LF"
CDS_LIB"pure_quanta"
WATTAGE"1/20W"
PART_NUMBER"CS00001JE10";
"B"
$PN"2"62;
"A"
$PN"1"54;
%"Q_RES"
"1","(-6350,4450)","0","pure_quanta","I14";
;
LOCATION"R6737"
$SEC"1"
CDS_SEC"1"
VALUE"0"
TOLERANCE"5%"
MATERIAL"CHIP"
PACK_TYPE"0201LF"
CDS_LIB"pure_quanta"
WATTAGE"1/20W"
PART_NUMBER"CS00001JE10";
"B"
$PN"2"65;
"A"
$PN"1"31;
%"Q_RES"
"1","(-2625,1275)","0","pure_quanta","I17";
;
LOCATION"R6738"
$SEC"1"
CDS_SEC"1"
VALUE"1K"
PACK_TYPE"0201LF"
MATERIAL"CHIP"
CDS_LIB"pure_quanta"
WATTAGE"1/20W"
TOLERANCE"1%"
PART_NUMBER"CS21001FE07";
"B"
$PN"2"34;
"A"
$PN"1"24;
%"Q_RES"
"1","(-2625,1200)","0","pure_quanta","I18";
;
LOCATION"R6739"
$SEC"1"
CDS_SEC"1"
MATERIAL"CHIP"
VALUE"1K"
PACK_TYPE"0201LF"
CDS_LIB"pure_quanta"
TOLERANCE"1%"
WATTAGE"1/20W"
PART_NUMBER"CS21001FE07";
"B"
$PN"2"35;
"A"
$PN"1"24;
%"Q_RES"
"1","(-6350,4350)","0","pure_quanta","I21";
;
LOCATION"R6747"
$SEC"1"
CDS_SEC"1"
TOLERANCE"5%"
MATERIAL"CHIP"
VALUE"0"
PACK_TYPE"0201LF"
CDS_LIB"pure_quanta"
WATTAGE"1/20W"
PART_NUMBER"CS00001JE10";
"B"
$PN"2"51;
"A"
$PN"1"29;
%"Q_RES"
"1","(-6350,4400)","0","pure_quanta","I22";
;
LOCATION"R6746"
$SEC"1"
CDS_SEC"1"
VALUE"0"
TOLERANCE"5%"
MATERIAL"CHIP"
PACK_TYPE"0201LF"
WATTAGE"1/20W"
CDS_LIB"pure_quanta"
PART_NUMBER"CS00001JE10";
"B"
$PN"2"64;
"A"
$PN"1"28;
%"Q_RES"
"1","(-6350,4250)","0","pure_quanta","I25";
;
LOCATION"R6749"
$SEC"1"
CDS_SEC"1"
VALUE"0"
TOLERANCE"5%"
MATERIAL"CHIP"
PACK_TYPE"0201LF"
WATTAGE"1/20W"
CDS_LIB"pure_quanta"
PART_NUMBER"CS00001JE10";
"B"
$PN"2"56;
"A"
$PN"1"30;
%"Q_RES"
"1","(-6350,4300)","0","pure_quanta","I26";
;
LOCATION"R6748"
$SEC"1"
CDS_SEC"1"
VALUE"0"
MATERIAL"CHIP"
PACK_TYPE"0201LF"
TOLERANCE"5%"
CDS_LIB"pure_quanta"
WATTAGE"1/20W"
PART_NUMBER"CS00001JE10";
"B"
$PN"2"55;
"A"
$PN"1"58;
%"Q_RES"
"1","(-2625,1100)","0","pure_quanta","I31";
;
LOCATION"R6750"
$SEC"1"
CDS_SEC"1"
MATERIAL"CHIP"
VALUE"1K"
PACK_TYPE"0201LF"
WATTAGE"1/20W"
TOLERANCE"1%"
CDS_LIB"pure_quanta"
PART_NUMBER"CS21001FE07";
"B"
$PN"2"37;
"A"
$PN"1"24;
%"Q_RES"
"1","(-2625,1025)","0","pure_quanta","I32";
;
LOCATION"R6751"
$SEC"1"
CDS_SEC"1"
MATERIAL"CHIP"
PACK_TYPE"0201LF"
VALUE"1K"
TOLERANCE"1%"
WATTAGE"1/20W"
CDS_LIB"pure_quanta"
PART_NUMBER"CS21001FE07";
"B"
$PN"2"36;
"A"
$PN"1"24;
%"Q_RES"
"1","(-2625,950)","0","pure_quanta","I35";
;
LOCATION"R6752"
$SEC"1"
CDS_SEC"1"
MATERIAL"CHIP"
PACK_TYPE"0201LF"
VALUE"1K"
WATTAGE"1/20W"
TOLERANCE"1%"
CDS_LIB"pure_quanta"
PART_NUMBER"CS21001FE07";
"B"
$PN"2"38;
"A"
$PN"1"24;
%"Q_RES"
"1","(-2625,875)","0","pure_quanta","I36";
;
LOCATION"R6753"
$SEC"1"
CDS_SEC"1"
MATERIAL"CHIP"
PACK_TYPE"0201LF"
VALUE"1K"
TOLERANCE"1%"
WATTAGE"1/20W"
CDS_LIB"pure_quanta"
PART_NUMBER"CS21001FE07";
"B"
$PN"2"39;
"A"
$PN"1"24;
%"Q_RES"
"1","(-3100,4600)","0","pure_quanta","I53";
;
LOCATION"R6754"
SEC"1"
VALUE"0"
TOLERANCE"5%"
MATERIAL"CHIP"
PACK_TYPE"0201LF"
WATTAGE"1/20W"
SEC_TYPE"0201LF"
CDS_LIB"pure_quanta"
PART_NUMBER"CS00001JE10";
"B"
$PN"2"15;
"A"
$PN"1"13;
%"Q_RES"
"1","(-3100,4550)","0","pure_quanta","I54";
;
LOCATION"R6755"
SEC"1"
MATERIAL"CHIP"
VALUE"0"
TOLERANCE"5%"
PACK_TYPE"0201LF"
CDS_LIB"pure_quanta"
SEC_TYPE"0201LF"
WATTAGE"1/20W"
PART_NUMBER"CS00001JE10";
"B"
$PN"2"10;
"A"
$PN"1"12;
%"Q_RES"
"1","(-3100,4400)","0","pure_quanta","I55";
;
LOCATION"R6758"
$SEC"1"
CDS_SEC"1"
TOLERANCE"5%"
VALUE"0"
MATERIAL"CHIP"
PACK_TYPE"0201LF"
CDS_LIB"pure_quanta"
WATTAGE"1/20W"
PART_NUMBER"CS00001JE10";
"B"
$PN"2"27;
"A"
$PN"1"60;
%"Q_RES"
"1","(-3100,4500)","0","pure_quanta","I56";
;
LOCATION"R6756"
$SEC"1"
CDS_SEC"1"
VALUE"0"
TOLERANCE"5%"
MATERIAL"CHIP"
PACK_TYPE"0201LF"
WATTAGE"1/20W"
CDS_LIB"pure_quanta"
PART_NUMBER"CS00001JE10";
"B"
$PN"2"16;
"A"
$PN"1"11;
%"Q_RES"
"1","(-3100,4450)","0","pure_quanta","I57";
;
LOCATION"R6757"
$SEC"1"
CDS_SEC"1"
VALUE"0"
TOLERANCE"5%"
MATERIAL"CHIP"
PACK_TYPE"0201LF"
WATTAGE"1/20W"
CDS_LIB"pure_quanta"
PART_NUMBER"CS00001JE10";
"B"
$PN"2"17;
"A"
$PN"1"61;
%"Q_RES"
"1","(-3100,4300)","0","pure_quanta","I58";
;
LOCATION"R6760"
$SEC"1"
CDS_SEC"1"
MATERIAL"CHIP"
TOLERANCE"5%"
VALUE"0"
PACK_TYPE"0201LF"
WATTAGE"1/20W"
CDS_LIB"pure_quanta"
PART_NUMBER"CS00001JE10";
"B"
$PN"2"26;
"A"
$PN"1"67;
%"Q_RES"
"1","(-3100,4350)","0","pure_quanta","I59";
;
LOCATION"R6759"
$SEC"1"
CDS_SEC"1"
TOLERANCE"5%"
MATERIAL"CHIP"
PACK_TYPE"0201LF"
VALUE"0"
WATTAGE"1/20W"
CDS_LIB"pure_quanta"
PART_NUMBER"CS00001JE10";
"B"
$PN"2"18;
"A"
$PN"1"66;
%"Q_RES"
"1","(-6350,4600)","0","pure_quanta","I6";
;
LOCATION"R6810"
SEC"1"
VALUE"0"
MATERIAL"CHIP"
PACK_TYPE"0201LF"
TOLERANCE"5%"
CDS_LIB"pure_quanta"
SEC_TYPE"0201LF"
WATTAGE"1/20W"
PART_NUMBER"CS00001JE10";
"B"
$PN"2"57;
"A"
$PN"1"50;
%"Q_RES"
"1","(-3100,4250)","0","pure_quanta","I60";
;
LOCATION"R6761"
$SEC"1"
CDS_SEC"1"
TOLERANCE"5%"
VALUE"0"
PACK_TYPE"0201LF"
MATERIAL"CHIP"
CDS_LIB"pure_quanta"
WATTAGE"1/20W"
PART_NUMBER"CS00001JE10";
"B"
$PN"2"19;
"A"
$PN"1"68;
%"Q_RES"
"1","(-6350,4550)","0","pure_quanta","I7";
;
LOCATION"R6811"
SEC"1"
MATERIAL"CHIP"
PACK_TYPE"0201LF"
VALUE"0"
TOLERANCE"5%"
CDS_LIB"pure_quanta"
SEC_TYPE"0201LF"
WATTAGE"1/20W"
PART_NUMBER"CS00001JE10";
"B"
$PN"2"63;
"A"
$PN"1"53;
%"Q_RES"
"1","(-5950,1525)","0","pure_quanta","I77";
;
LOCATION"R6762"
$SEC"1"
CDS_SEC"1"
WATTAGE"1/20W"
TOLERANCE"1%"
VALUE"1K"
MATERIAL"CHIP"
PACK_TYPE"0201LF"
CDS_LIB"pure_quanta"
PART_NUMBER"CS21001FE07";
"B"
$PN"2"40;
"A"
$PN"1"23;
%"Q_RES"
"1","(-5950,1425)","0","pure_quanta","I78";
;
LOCATION"R6763"
$SEC"1"
CDS_SEC"1"
VALUE"1K"
MATERIAL"CHIP"
PACK_TYPE"0201LF"
CDS_LIB"pure_quanta"
WATTAGE"1/20W"
TOLERANCE"1%"
PART_NUMBER"CS21001FE07";
"B"
$PN"2"41;
"A"
$PN"1"23;
%"Q_RES"
"1","(-5950,1350)","0","pure_quanta","I79";
;
LOCATION"R6764"
$SEC"1"
CDS_SEC"1"
MATERIAL"CHIP"
PACK_TYPE"0201LF"
VALUE"1K"
TOLERANCE"1%"
WATTAGE"1/20W"
CDS_LIB"pure_quanta"
PART_NUMBER"CS21001FE07";
"B"
$PN"2"52;
"A"
$PN"1"23;
%"P1V0"
"1","(-3150,1750)","0","pure_quanta_power","I8";
;
HDL_POWER"P1V8_CPU1_RT_1D"
CDS_LIB"pure_quanta_power";
"A"24;
%"Q_RES"
"1","(-5950,1275)","0","pure_quanta","I80";
;
LOCATION"R6765"
$SEC"1"
CDS_SEC"1"
MATERIAL"CHIP"
PACK_TYPE"0201LF"
VALUE"1K"
WATTAGE"1/20W"
TOLERANCE"1%"
CDS_LIB"pure_quanta"
PART_NUMBER"CS21001FE07";
"B"
$PN"2"42;
"A"
$PN"1"23;
%"P1V0"
"1","(-6475,1825)","0","pure_quanta_power","I81";
;
HDL_POWER"P1V8_CPU0_RT_1D"
CDS_LIB"pure_quanta_power";
"A"23;
%"Q_RES"
"1","(-5950,1100)","0","pure_quanta","I82";
;
LOCATION"R6767"
$SEC"1"
CDS_SEC"1"
VALUE"1K"
MATERIAL"CHIP"
PACK_TYPE"0201LF"
CDS_LIB"pure_quanta"
WATTAGE"1/20W"
TOLERANCE"1%"
PART_NUMBER"CS21001FE07";
"B"
$PN"2"44;
"A"
$PN"1"23;
%"Q_RES"
"1","(-5950,1175)","0","pure_quanta","I83";
;
LOCATION"R6766"
$SEC"1"
CDS_SEC"1"
PACK_TYPE"0201LF"
VALUE"1K"
MATERIAL"CHIP"
CDS_LIB"pure_quanta"
TOLERANCE"1%"
WATTAGE"1/20W"
PART_NUMBER"CS21001FE07";
"B"
$PN"2"43;
"A"
$PN"1"23;
%"Q_RES"
"1","(-5950,1025)","0","pure_quanta","I84";
;
LOCATION"R6768"
$SEC"1"
CDS_SEC"1"
VALUE"1K"
MATERIAL"CHIP"
PACK_TYPE"0201LF"
CDS_LIB"pure_quanta"
TOLERANCE"1%"
WATTAGE"1/20W"
PART_NUMBER"CS21001FE07";
"B"
$PN"2"45;
"A"
$PN"1"23;
%"Q_RES"
"1","(-5950,950)","0","pure_quanta","I85";
;
LOCATION"R6769"
$SEC"1"
CDS_SEC"1"
VALUE"1K"
MATERIAL"CHIP"
PACK_TYPE"0201LF"
CDS_LIB"pure_quanta"
WATTAGE"1/20W"
TOLERANCE"1%"
PART_NUMBER"CS21001FE07";
"B"
$PN"2"46;
"A"
$PN"1"23;
%"UNIVERSAL_GND"
"1","(-4250,3975)","0","pure_quanta_power","I86";
;
CDS_LIB"pure_quanta_power"
HDL_POWER"GND";
"A"3;
%"P1V0_AUX"
"1","(-5475,5600)","0","pure_quanta_power","I87";
;
HDL_POWER"P1V8_AUX"
CDS_LIB"pure_quanta_power";
"A"22;
%"Q_CAP"
"1","(-5650,5350)","2","pure_quanta","I88";
;
LOCATION"C7500"
$SEC"1"
CDS_SEC"1"
VOLTAGE"10V"
TOLERANCE"10%"
MATERIAL"X7S"
VALUE"0.1UF"
PACK_TYPE"C0201"
CDS_LIB"pure_quanta"
PART_NUMBER"CH4102K6E00";
"B"
$PN"2"4;
"A"
$PN"1"22;
%"UNIVERSAL_GND"
"1","(-5650,5050)","0","pure_quanta_power","I89";
;
CDS_LIB"pure_quanta_power"
HDL_POWER"GND";
"A"4;
%"Q_RES"
"1","(-2625,1450)","0","pure_quanta","I9";
;
LOCATION"R6718"
$SEC"1"
CDS_SEC"1"
TOLERANCE"1%"
WATTAGE"1/20W"
PACK_TYPE"0201LF"
MATERIAL"CHIP"
VALUE"1K"
CDS_LIB"pure_quanta"
PART_NUMBER"CS21001FE07";
"B"
$PN"2"32;
"A"
$PN"1"24;
%"UNIVERSAL_GND"
"1","(-8600,600)","0","pure_quanta_power","I93";
;
CDS_LIB"pure_quanta_power"
HDL_POWER"GND";
"A"21;
%"Q_RES"
"2","(-8600,1025)","0","pure_quanta","I94";
;
LOCATION"R6773"
$SEC"1"
CDS_SEC"1"
WATTAGE"1/20W"
TOLERANCE"5%"
PACK_TYPE"0201LF"
VALUE"4.7K"
MATERIAL"CHIP"
CDS_LIB"pure_quanta"
PART_NUMBER"CS24701JE04";
"A"
$PN"1"47;
"B"
$PN"2"21;
%"Q_RES"
"2","(-8300,1025)","0","pure_quanta","I95";
;
LOCATION"R6774"
$SEC"1"
CDS_SEC"1"
VALUE"4.7K"
TOLERANCE"5%"
PACK_TYPE"0201LF"
MATERIAL"CHIP"
WATTAGE"1/20W"
CDS_LIB"pure_quanta"
PART_NUMBER"CS24701JE04";
"A"
$PN"1"49;
"B"
$PN"2"21;
%"Q_RES"
"2","(-8600,1800)","0","pure_quanta","I96";
;
LOCATION"R6770"
$SEC"1"
CDS_SEC"1"
PACK_TYPE"0201LF"
TOLERANCE"5%"
WATTAGE"1/20W"
VALUE"4.7K"
MATERIAL"EMPTY"
CDS_LIB"pure_quanta"
PART_NUMBER"CS24701JE04";
"A"
$PN"1"25;
"B"
$PN"2"47;
%"Q_RES"
"2","(-7950,1025)","0","pure_quanta","I97";
;
LOCATION"R6775"
$SEC"1"
CDS_SEC"1"
VALUE"4.7K"
PACK_TYPE"0201LF"
MATERIAL"CHIP"
WATTAGE"1/20W"
TOLERANCE"5%"
CDS_LIB"pure_quanta"
PART_NUMBER"CS24701JE04";
"A"
$PN"1"48;
"B"
$PN"2"21;
%"Q_RES"
"2","(-7950,1775)","0","pure_quanta","I98";
;
LOCATION"R6772"
$SEC"1"
CDS_SEC"1"
VALUE"4.7K"
WATTAGE"1/20W"
TOLERANCE"5%"
PACK_TYPE"0201LF"
MATERIAL"EMPTY"
CDS_LIB"pure_quanta"
PART_NUMBER"CS24701JE04";
"A"
$PN"1"25;
"B"
$PN"2"48;
END.
